# BASEBOARD_FAB2 (Tioga Pass) — schematic parts with pin connectivity, parts 4650–4650 of 4751; source: Cadence DE-HDL packaged netlist (pstxprt.dat, pstxnet.dat, pstchip.dat)

U2D1  SKX_EXT_B  IC  pkg BGA1  page 55  (pins 2705-3042 of 3647)
  DW30  VSS(69)  GROUND  = GND
  DW32  DDR4_DQS_DP(14)  BI  = M_L_DQS_DP<14>
  DW34  VSS(68)  GROUND  = GND
  DW36  VSS(67)  GROUND  = GND
  DW38  DDR3_DQS_DP(13)  BI  = M_K_DQS_DP<13>
  DW40  VSS(66)  GROUND  = GND
  DW42  DDR4_DQ(33)  BI  = M_L_DQ<33>
  DW44  RSVD(23)  BI  = TP_CPU1_RSVD_23
  DW46  RSVD(22)  BI  = TP_CPU1_RSVD_22
  DW48  DDR3_MA(13)  OUT  = M_K_MA<13>
  DW50  DDR4_CS_N(4)  OUT  = M_L_CS_N<4>
  DW52  DDR4_MA(0)  OUT  = M_L_MA<0>
  DW54  DDR3_MA(10)  OUT  = M_K_MA<10>
  DW56  DDR3_CLK_DN(2)  OUT  = M_K_CLK_DN<2>
  DW58  DDR4_MA(1)  OUT  = M_L_MA<1>
  DW60  DDR3_ACT_N  OUT  = M_K_ACT_N
  DW62  DDR3_BG(1)  OUT  = M_K_BG<1>
  DW64  VSS(65)  GROUND  = GND
  DW66  VSS(64)  GROUND  = GND
  DW68  VSS(63)  GROUND  = GND
  DW70  VSS(62)  GROUND  = GND
  DW72  VSS(61)  GROUND  = GND
  DW74  VSS(60)  GROUND  = GND
  DW76  VSS(59)  GROUND  = GND
  DW78  DDR4_DQ(22)  BI  = M_L_DQ<22>
  DW80  DDR4_DQ(16)  BI  = M_L_DQ<16>
  DW82  VSS(57)  GROUND  = GND
  DW84  VSS(56)  GROUND  = GND
  DY3  RSVD(21)  BI  = TP_CPU1_RSVD_21
  DY5  VSS(55)  GROUND  = GND
  DY7  PE1_TX_DN(13)  OUT  = TP_P3E_CPU1_PE1_RSR3_TXN<13>
  DY9  PE3_TX_DP(4)  OUT  = P3E_CPU1_PE3_MP_TXP<4>
  DY11  PE3_TX_DN(3)  OUT  = P3E_CPU1_PE3_MP_TXN<3>
  DY13  PE1_RX_DP(13)  IN  = TP_P3E_CPU1_PE1_RSR3_RXP<13>
  DY15  PE1_RX_DN(14)  IN  = TP_P3E_CPU1_PE1_RSR3_RXN<14>
  DY17  PE3_RX_DP(0)  IN  = P3E_CPU1_PE3_MP_RXP<0>
  DY19  VSS(54)  GROUND  = GND
  DY21  DDR3_DQ(58)  BI  = M_K_DQ<58>
  DY23  VSS(53)  GROUND  = GND
  DY25  DDR4_DQ(54)  BI  = M_L_DQ<54>
  DY27  DDR4_DQ(52)  BI  = M_L_DQ<52>
  DY29  VSS(52)  GROUND  = GND
  DY31  DDR4_DQ(46)  BI  = M_L_DQ<46>
  DY33  DDR4_DQ(44)  BI  = M_L_DQ<44>
  DY35  VSS(51)  GROUND  = GND
  DY37  DDR3_DQ(38)  BI  = M_K_DQ<38>
  DY39  DDR3_DQ(36)  BI  = M_K_DQ<36>
  DY41  VSS(50)  GROUND  = GND
  DY45  VSS(1215)  GROUND  = GND
  DY47  VSS(1216)  GROUND  = GND
  DY49  VSS(1217)  GROUND  = GND
  DY51  VSS(1218)  GROUND  = GND
  DY53  VSS(1219)  GROUND  = GND
  DY55  VSS(1220)  GROUND  = GND
  DY57  VSS(1221)  GROUND  = GND
  DY59  VSS(1222)  GROUND  = GND
  DY61  VSS(1223)  GROUND  = GND
  DY63  VSS(1224)  GROUND  = GND
  DY65  DDR4_ECC(3)  BI  = M_L_ECC<3>
  DY67  DDR4_DQS_DP(8)  BI  = M_L_DQS_DP<8>
  DY69  DDR4_ECC(0)  BI  = M_L_ECC<0>
  DY71  VSS(49)  GROUND  = GND
  DY73  DDR4_DQS_DP(12)  BI  = M_L_DQS_DP<12>
  DY75  VSS(48)  GROUND  = GND
  DY77  DDR4_DQ(18)  BI  = M_L_DQ<18>
  DY79  DDR4_DQS_DN(11)  BI  = M_L_DQS_DN<11>
  DY81  DDR4_DQ(20)  BI  = M_L_DQ<20>
  DY83  DDR3_DQ(11)  BI  = M_K_DQ<11>
  DY85  VSS(1242)  GROUND  = GND
  E2  RSVD(283)  BI  = TP_CPU1_RSVD_283
  E4  RSVD(282)  BI  = TP_CPU1_RSVD_282
  E6  VSS(1154)  GROUND  = GND
  E8  VSS(1153)  GROUND  = GND
  E10  UPI1_TX_DP(8)  OUT  = UPI_CPU1_CPU0_P1P1_DN<8>
  E12  UPI1_TX_DN(10)  OUT  = UPI_CPU1_CPU0_P1P1_DN<10>
  E14  UPI1_TX_DP(12)  OUT  = UPI_CPU1_CPU0_P1P1_DP<12>
  E16  VSS(1152)  GROUND  = GND
  E18  VSS(1151)  GROUND  = GND
  E20  VSS(1150)  GROUND  = GND
  E22  VSS(1149)  GROUND  = GND
  E24  RSVD(281)  BI  = TP_CPU1_RSVD_281
  E26  DDR1_DQ(51)  BI  = M_H_DQ<51>
  E28  DDR1_DQS_DP(6)  BI  = M_H_DQS_DP<6>
  E30  DDR1_DQ(52)  BI  = M_H_DQ<52>
  E32  DDR1_DQ(43)  BI  = M_H_DQ<43>
  E34  DDR1_DQS_DP(5)  BI  = M_H_DQS_DP<5>
  E36  DDR1_DQ(44)  BI  = M_H_DQ<44>
  E38  DDR0_DQ(35)  BI  = M_G_DQ<35>
  E40  DDR0_DQS_DP(4)  BI  = M_G_DQS_DP<4>
  E42  DDR0_DQ(36)  BI  = M_G_DQ<36>
  E46  VCCD012(3)  POWER  = PVDDQ_GHJ
  E48  VCCD012(4)  POWER  = PVDDQ_GHJ
  E50  VCCD012(5)  POWER  = PVDDQ_GHJ
  E52  VCCD012(6)  POWER  = PVDDQ_GHJ
  E54  VCCD012(7)  POWER  = PVDDQ_GHJ
  E56  VCCD012(8)  POWER  = PVDDQ_GHJ
  E58  VCCD012(9)  POWER  = PVDDQ_GHJ
  E60  VCCD012(10)  POWER  = PVDDQ_GHJ
  E62  VCCD012(11)  POWER  = PVDDQ_GHJ
  E64  VCCD012(12)  POWER  = PVDDQ_GHJ
  E66  VSS(1228)  GROUND  = GND
  E72  VSS(1148)  GROUND  = GND
  E74  VSS(1147)  GROUND  = GND
  E76  VSS(1146)  GROUND  = GND
  E78  DDR1_DQ(22)  BI  = M_H_DQ<22>
  E80  DDR1_DQ(16)  BI  = M_H_DQ<16>
  E82  VSS(1244)  GROUND  = GND
  E84  RSVD(280)  BI  = TP_CPU1_RSVD_280
  EA4  RSVD(20)  BI  = TP_CPU1_RSVD_20
  EA6  VSS(47)  GROUND  = GND
  EA8  PE1_TX_DN(14)  OUT  = TP_P3E_CPU1_PE1_RSR3_TXN<14>
  EA10  PE3_TX_DP(3)  OUT  = P3E_CPU1_PE3_MP_TXP<3>
  EA12  VCCIO(67)  POWER  = PVCCIO_CPU1
  EA14  VSS(1225)  GROUND  = GND
  EA16  VSS(45)  GROUND  = GND
  EA18  PE3_RX_DN(0)  IN  = P3E_CPU1_PE3_MP_RXN<0>
  EA20  VSS(44)  GROUND  = GND
  EA22  VSS(43)  GROUND  = GND
  EA24  DDR4_DQ(50)  BI  = M_L_DQ<50>
  EA26  DDR4_DQS_DN(15)  BI  = M_L_DQS_DN<15>
  EA28  DDR4_DQ(53)  BI  = M_L_DQ<53>
  EA30  DDR4_DQ(42)  BI  = M_L_DQ<42>
  EA32  DDR4_DQS_DN(14)  BI  = M_L_DQS_DN<14>
  EA34  DDR4_DQ(45)  BI  = M_L_DQ<45>
  EA36  DDR3_DQ(34)  BI  = M_K_DQ<34>
  EA38  DDR3_DQS_DN(13)  BI  = M_K_DQS_DN<13>
  EA40  DDR3_DQ(37)  BI  = M_K_DQ<37>
  EA42  VSS(42)  GROUND  = GND
  EA44  RSVD(19)  BI  = TP_CPU1_RSVD_19
  EA46  DDR3_MA(17)  OUT  = M_K_MA<17>
  EA48  DDR3_ODT(3)  OUT  = M_K_ODT<3>
  EA50  DDR3_ODT(2)  OUT  = M_K_ODT<2>
  EA52  DDR3_MA(16)  OUT  = M_K_MA<16>
  EA54  DDR3_BA(1)  OUT  = M_K_BA<1>
  EA56  DDR3_CLK_DP(2)  OUT  = M_K_CLK_DP<2>
  EA58  DDR3_MA(5)  OUT  = M_K_MA<5>
  EA60  DDR3_MA(7)  OUT  = M_K_MA<7>
  EA62  DDR3_CKE(2)  OUT  = M_K_CKE<2>
  EA64  VSS(41)  GROUND  = GND
  EA66  DDR4_ECC(7)  BI  = M_L_ECC<7>
  EA68  DDR4_ECC(1)  BI  = M_L_ECC<1>
  EA70  VSS(40)  GROUND  = GND
  EA72  DDR4_DQ(30)  BI  = M_L_DQ<30>
  EA74  DDR4_DQ(28)  BI  = M_L_DQ<28>
  EA76  VSS(39)  GROUND  = GND
  EA78  VSS(38)  GROUND  = GND
  EA80  VSS(37)  GROUND  = GND
  EA82  VSS(36)  GROUND  = GND
  EA84  VSS(1241)  GROUND  = GND
  EB3  RSVD(18)  BI  = TP_CPU1_RSVD_18
  EB5  RSVD(17)  BI  = TP_CPU1_RSVD_17
  EB7  PE1_TX_DP(14)  OUT  = TP_P3E_CPU1_PE1_RSR3_TXP<14>
  EB9  PE3_TX_DN(4)  OUT  = P3E_CPU1_PE3_MP_TXN<4>
  EB11  PE3_TX_DP(2)  OUT  = P3E_CPU1_PE3_MP_TXP<2>
  EB13  VSS(35)  GROUND  = GND
  EB15  VCCIO(68)  POWER  = PVCCIO_CPU1
  EB21  DDR3_DQ(59)  BI  = M_K_DQ<59>
  EB23  VSS(33)  GROUND  = GND
  EB25  VSS(32)  GROUND  = GND
  EB27  VSS(31)  GROUND  = GND
  EB29  VSS(30)  GROUND  = GND
  EB31  VSS(29)  GROUND  = GND
  EB33  VSS(28)  GROUND  = GND
  EB35  VSS(27)  GROUND  = GND
  EB37  VSS(26)  GROUND  = GND
  EB39  VSS(25)  GROUND  = GND
  EB41  VSS(24)  GROUND  = GND
  EB45  DDR3_CS_N(7)  OUT  = M_K_CS_N<7>
  EB47  DDR3_CS_N(3)  OUT  = M_K_CS_N<3>
  EB49  DDR3_CS_N(5)  OUT  = M_K_CS_N<5>
  EB51  DDR3_CS_N(4)  OUT  = M_K_CS_N<4>
  EB53  DDR3_MA(0)  OUT  = M_K_MA<0>
  EB55  DDR3_CLK_DP(0)  OUT  = M_K_CLK_DP<0>
  EB57  DDR3_MA(3)  OUT  = M_K_MA<3>
  EB59  DDR3_MA(8)  OUT  = M_K_MA<8>
  EB61  DDR3_MA(11)  OUT  = M_K_MA<11>
  EB63  DDR3_CKE(3)  OUT  = M_K_CKE<3>
  EB65  VSS(23)  GROUND  = GND
  EB67  DDR4_DQS_DN(8)  BI  = M_L_DQS_DN<8>
  EB69  VSS(22)  GROUND  = GND
  EB71  DDR4_DQ(26)  BI  = M_L_DQ<26>
  EB73  DDR4_DQS_DN(12)  BI  = M_L_DQS_DN<12>
  EB75  DDR4_DQ(29)  BI  = M_L_DQ<29>
  EB77  DDR4_DQ(19)  BI  = M_L_DQ<19>
  EB79  DDR4_DQS_DP(2)  BI  = M_L_DQS_DP<2>
  EB81  DDR4_DQ(21)  BI  = M_L_DQ<21>
  EB83  VSS(1240)  GROUND  = GND
  EB85  RSVD(16)  BI  = TP_CPU1_RSVD_16
  EC4  RSVD(14)  BI  = TP_CPU1_RSVD_14
  EC6  VSS(1237)  GROUND  = GND
  EC8  PE1_TX_DP(15)  OUT  = TP_P3E_CPU1_PE1_RSR3_TXP<15>
  EC10  VSS(21)  GROUND  = GND
  EC12  PE3_TX_DN(2)  OUT  = P3E_CPU1_PE3_MP_TXN<2>
  EC14  PE3_TX_DP(0)  OUT  = P3E_CPU1_PE3_MP_TXP<0>
  EC16  RSVD(15)  BI  = TP_CPU1_RSVD_15
  EC22  DDR3_DQ(62)  BI  = M_K_DQ<62>
  EC24  DDR4_DQ(51)  BI  = M_L_DQ<51>
  EC26  DDR4_DQS_DP(6)  BI  = M_L_DQS_DP<6>
  EC28  DDR4_DQ(48)  BI  = M_L_DQ<48>
  EC30  DDR4_DQ(43)  BI  = M_L_DQ<43>
  EC32  DDR4_DQS_DP(5)  BI  = M_L_DQS_DP<5>
  EC34  DDR4_DQ(40)  BI  = M_L_DQ<40>
  EC36  DDR3_DQ(35)  BI  = M_K_DQ<35>
  EC38  DDR3_DQS_DP(4)  BI  = M_K_DQS_DP<4>
  EC40  DDR3_DQ(32)  BI  = M_K_DQ<32>
  EC42  VSS(1238)  GROUND  = GND
  EC44  RSVD(13)  BI  = TP_CPU1_RSVD_13
  EC46  VCCD345(11)  POWER  = PVDDQ_KLM
  EC48  VCCD345(10)  POWER  = PVDDQ_KLM
  EC50  VCCD345(9)  POWER  = PVDDQ_KLM
  EC52  VCCD345(8)  POWER  = PVDDQ_KLM
  EC54  VCCD345(7)  POWER  = PVDDQ_KLM
  EC56  VCCD345(6)  POWER  = PVDDQ_KLM
  EC58  VCCD345(5)  POWER  = PVDDQ_KLM
  EC60  VCCD345(4)  POWER  = PVDDQ_KLM
  EC62  VCCD345(3)  POWER  = PVDDQ_KLM
  EC70  VSS(20)  GROUND  = GND
  EC72  VSS(19)  GROUND  = GND
  EC74  VSS(18)  GROUND  = GND
  EC76  VSS(17)  GROUND  = GND
  EC78  DDR4_DQ(23)  BI  = M_L_DQ<23>
  EC80  DDR4_DQ(17)  BI  = M_L_DQ<17>
  EC82  VSS(1236)  GROUND  = GND
  EC84  RSVD(12)  BI  = TP_CPU1_RSVD_12
  ED5  RSVD(10)  BI  = TP_CPU1_RSVD_10
  ED7  VSS(1234)  GROUND  = GND
  ED9  PE1_TX_DN(15)  OUT  = TP_P3E_CPU1_PE1_RSR3_TXN<15>
  ED11  VSS(16)  GROUND  = GND
  ED13  PE3_TX_DP(1)  OUT  = P3E_CPU1_PE3_MP_TXP<1>
  ED15  VSS(15)  GROUND  = GND
  ED23  VSS(14)  GROUND  = GND
  ED25  DDR4_DQ(55)  BI  = M_L_DQ<55>
  ED27  DDR4_DQ(49)  BI  = M_L_DQ<49>
  ED29  VSS(13)  GROUND  = GND
  ED31  DDR4_DQ(47)  BI  = M_L_DQ<47>
  ED33  DDR4_DQ(41)  BI  = M_L_DQ<41>
  ED35  VSS(12)  GROUND  = GND
  ED37  DDR3_DQ(39)  BI  = M_K_DQ<39>
  ED39  DDR3_DQ(33)  BI  = M_K_DQ<33>
  ED41  VSS(1235)  GROUND  = GND
  ED45  RSVD(11)  BI  = TP_CPU1_RSVD_11
  ED47  DDR3_CS_N(2)  OUT  = M_K_CS_N<2>
  ED49  DDR3_CS_N(1)  OUT  = M_K_CS_N<1>
  ED51  DDR3_MA(14)  OUT  = M_K_MA<14>
  ED53  DDR3_PAR  OUT  = M_K_PAR
  ED55  DDR3_CLK_DN(0)  OUT  = M_K_CLK_DN<0>
  ED57  DDR3_MA(1)  OUT  = M_K_MA<1>
  ED59  DDR3_MA(4)  OUT  = M_K_MA<4>
  ED61  DDR3_BG(0)  OUT  = M_K_BG<0>
  ED63  DDR3_ALERT_N  IN  = M_K_ALERT_N
  ED69  VSS(1229)  GROUND  = GND
  ED71  DDR4_DQ(27)  BI  = M_L_DQ<27>
  ED73  DDR4_DQS_DP(3)  BI  = M_L_DQS_DP<3>
  ED75  DDR4_DQ(24)  BI  = M_L_DQ<24>
  ED77  VSS(11)  GROUND  = GND
  ED79  DDR4_DQS_DN(2)  BI  = M_L_DQS_DN<2>
  ED81  VSS(1233)  GROUND  = GND
  ED83  RSVD(9)  BI  = TP_CPU1_RSVD_9
  EE6  RSVD(6)  BI  = TP_CPU1_RSVD_6
  EE8  VSS(1231)  GROUND  = GND
  EE10  VCCIO(0)  POWER  = PVCCIO_CPU1
  EE12  PE3_TX_DN(1)  OUT  = P3E_CPU1_PE3_MP_TXN<1>
  EE14  PE3_TX_DN(0)  OUT  = P3E_CPU1_PE3_MP_TXN<0>
  EE16  RSVD(8)  BI  = TP_CPU1_RSVD_8
  EE24  VSS(10)  GROUND  = GND
  EE26  DDR4_DQS_DN(6)  BI  = M_L_DQS_DN<6>
  EE28  VSS(9)  GROUND  = GND
  EE30  VSS(8)  GROUND  = GND
  EE32  DDR4_DQS_DN(5)  BI  = M_L_DQS_DN<5>
  EE34  VSS(7)  GROUND  = GND
  EE36  VSS(6)  GROUND  = GND
  EE38  DDR3_DQS_DN(4)  BI  = M_K_DQS_DN<4>
  EE40  VSS(1232)  GROUND  = GND
  EE44  VCCD345(50)  POWER  = PVDDQ_KLM
  EE46  RSVD(7)  BI  = TP_CPU1_RSVD_7
  EE48  DDR3_ODT(1)  OUT  = M_K_ODT<1>
  EE50  DDR3_ODT(0)  OUT  = M_K_ODT<0>
  EE52  DDR3_BA(0)  OUT  = M_K_BA<0>
  EE54  DDR3_CLK_DP(1)  OUT  = M_K_CLK_DP<1>
  EE56  DDR3_CLK_DP(3)  OUT  = M_K_CLK_DP<3>
  EE58  DDR3_MA(2)  OUT  = M_K_MA<2>
  EE60  DDR3_MA(6)  OUT  = M_K_MA<6>
  EE62  DDR3_CKE(0)  OUT  = M_K_CKE<0>
  EE70  VSS(5)  GROUND  = GND
  EE72  DDR4_DQ(31)  BI  = M_L_DQ<31>
  EE74  DDR4_DQ(25)  BI  = M_L_DQ<25>
  EE76  VSS(4)  GROUND  = GND
  EE78  VSS(3)  GROUND  = GND
  EE80  VSS(1230)  GROUND  = GND
  EE82  RSVD(5)  BI  = TP_CPU1_RSVD_5
  EE84  RSVD(4)  BI  = TP_CPU1_RSVD_4
  EF45  VCCD345(49)  POWER  = PVDDQ_KLM
  EF47  RSVD(3)  BI  = TP_CPU1_RSVD_3
  EF49  VCCD345(2)  POWER  = PVDDQ_KLM
  EF51  DDR3_CS_N(0)  OUT  = M_K_CS_N<0>
  EF53  VCCD345(1)  POWER  = PVDDQ_KLM
  EF55  DDR3_CLK_DN(1)  OUT  = M_K_CLK_DN<1>
  EF57  DDR3_CLK_DN(3)  OUT  = M_K_CLK_DN<3>
  EF59  VCCD345(0)  POWER  = PVDDQ_KLM
  EF61  DDR3_MA(9)  OUT  = M_K_MA<9>
  EF63  DDR3_CKE(1)  OUT  = M_K_CKE<1>
  EF71  VSS(2)  GROUND  = GND
  EF73  DDR4_DQS_DN(3)  BI  = M_L_DQS_DN<3>
  EF75  VSS(1)  GROUND  = GND
  EF77  RSVD(2)  BI  = TP_CPU1_RSVD_2
  EF79  VSS(0)  GROUND  = GND
  EF81  RSVD(1)  BI  = TP_CPU1_RSVD_1
  EF83  RSVD(0)  BI  = TP_CPU1_RSVD_0
  F3  RSVD(279)  BI  = TP_CPU1_RSVD_279
  F5  VSS(1145)  GROUND  = GND
  F7  UPI1_TX_DP(4)  OUT  = UPI_CPU1_CPU0_P1P1_DP<4>
  F9  UPI1_TX_DP(7)  OUT  = UPI_CPU1_CPU0_P1P1_DN<7>
  F11  UPI1_TX_DN(8)  OUT  = UPI_CPU1_CPU0_P1P1_DP<8>
  F13  UPI1_TX_DP(11)  OUT  = UPI_CPU1_CPU0_P1P1_DN<11>
  F15  UPI1_TX_DN(13)  OUT  = UPI_CPU1_CPU0_P1P1_DN<13>
  F17  VSS(1144)  GROUND  = GND
  F19  VSS(1143)  GROUND  = GND
  F21  UPI1_TX_DN(18)  OUT  = UPI_CPU1_CPU0_P1P1_DP<18>
  F23  RSVD(278)  BI  = TP_CPU1_RSVD_278
  F25  VSS(1142)  GROUND  = GND
  F27  DDR1_DQ(55)  BI  = M_H_DQ<55>
  F29  DDR1_DQ(53)  BI  = M_H_DQ<53>
  F31  VSS(1141)  GROUND  = GND
  F33  DDR1_DQ(47)  BI  = M_H_DQ<47>
  F35  DDR1_DQ(45)  BI  = M_H_DQ<45>
  F37  VSS(1140)  GROUND  = GND
  F39  DDR0_DQ(39)  BI  = M_G_DQ<39>
  F41  DDR0_DQ(37)  BI  = M_G_DQ<37>
  F43  VSS(1139)  GROUND  = GND
  F45  DDR0_CS_N(6)  OUT  = M_G_CS_N<6>
  F47  DDR0_CS_N(3)  OUT  = M_G_CS_N<3>
  F49  DDR0_CS_N(1)  OUT  = M_G_CS_N<1>
  F51  DDR0_MA(14)  OUT  = M_G_MA<14>
  F53  DDR0_MA(0)  OUT  = M_G_MA<0>
  F55  DDR0_CLK_DN(0)  OUT  = M_G_CLK_DN<0>
  F57  DDR0_MA(1)  OUT  = M_G_MA<1>
  F59  DDR0_MA(5)  OUT  = M_G_MA<5>
  F61  DDR0_MA(9)  OUT  = M_G_MA<9>
